(kicad_pcb
	(version 20260206)
	(generator "pcbnew")
	(generator_version "10.0")
	(general
		(thickness 1.6)
		(legacy_teardrops no)
	)
	(paper "A4")
	(title_block
		(title "01162023_DA0F0TEBIF0_F0T_Expander_BD_F_brd_V02_OCP.brd")
		(comment 1 "Grand Teton / footprints 4893-4898 of 9728")
	)
	(layers
		(0 "F.Cu" signal "TOP")
		(4 "In1.Cu" signal "GND")
		(6 "In2.Cu" signal "VCC")
		(8 "In3.Cu" signal "VCC1")
		(10 "In4.Cu" signal "GND1")
		(12 "In5.Cu" signal "IN1")
		(14 "In6.Cu" signal "GND2")
		(16 "In7.Cu" signal "IN2")
		(18 "In8.Cu" signal "GND3")
		(20 "In9.Cu" signal "IN3")
		(22 "In10.Cu" signal "GND4")
		(24 "In11.Cu" signal "IN4")
		(26 "In12.Cu" signal "GND5")
		(28 "In13.Cu" signal "IN5")
		(30 "In14.Cu" signal "GND6")
		(32 "In15.Cu" signal "IN6")
		(34 "In16.Cu" signal "GND7")
		(2 "B.Cu" signal "BOTTOM")
		(9 "F.Adhes" user "F.Adhesive")
		(11 "B.Adhes" user "B.Adhesive")
		(13 "F.Paste" user "Package Geometry/Pastemask Top")
		(15 "B.Paste" user "Package Geometry/Pastemask Bottom")
		(5 "F.SilkS" user "Ref Des/Silkscreen Top")
		(7 "B.SilkS" user "Ref Des/Silkscreen Bottom")
		(1 "F.Mask" user "Board Geometry/Soldermask Top")
		(3 "B.Mask" user "Board Geometry/Soldermask Bottom")
		(17 "Dwgs.User" user "User.Drawings")
		(19 "Cmts.User" user "User.Comments")
		(21 "Eco1.User" user "User.Eco1")
		(23 "Eco2.User" user "User.Eco2")
		(25 "Edge.Cuts" user "Board Geometry/Outline")
		(27 "Margin" user)
		(31 "F.CrtYd" user "Package Geometry/Place Bound Top")
		(29 "B.CrtYd" user "Package Geometry/Place Bound Bottom")
		(35 "F.Fab" user "Ref Des/Assembly Top")
		(33 "B.Fab" user "Ref Des/Assembly Bottom")
	)
	(footprint ""
		(layer "F.Cu")
		(at 444.226442 -25.432004 -90)
		(property "Reference" "C980"
			(at 0 0 270)
			(layer "F.SilkS")
			(hide yes)
			(effects
				(font
					(size 1.27 1.27)
				)
			)
		)
		(property "Value" ""
			(at 0 0 270)
			(layer "F.Fab")
			(effects
				(font
					(size 1.27 1.27)
				)
			)
		)
		(duplicate_pad_numbers_are_jumpers no)
		(fp_line
			(start -0.7874 0.4064)
			(end -0.7874 -0.4064)
			(stroke
				(width 0.1524)
				(type default)
			)
			(layer "F.SilkS")
		)
		(fp_line
			(start 0.7874 0.4064)
			(end -0.7874 0.4064)
			(stroke
				(width 0.1524)
				(type default)
			)
			(layer "F.SilkS")
		)
		(fp_line
			(start -0.7874 -0.4064)
			(end 0.7874 -0.4064)
			(stroke
				(width 0.1524)
				(type default)
			)
			(layer "F.SilkS")
		)
		(fp_line
			(start 0.7874 -0.4064)
			(end 0.7874 0.4064)
			(stroke
				(width 0.1524)
				(type default)
			)
			(layer "F.SilkS")
		)
		(fp_line
			(start -0.67945 0.3048)
			(end -0.67945 -0.305054)
			(stroke
				(width 0.1)
				(type default)
			)
			(layer "F.Fab")
		)
		(fp_line
			(start -0.12065 0.3048)
			(end -0.67945 0.3048)
			(stroke
				(width 0.1)
				(type default)
			)
			(layer "F.Fab")
		)
		(fp_line
			(start 0.120396 0.3048)
			(end 0.120396 0.2794)
			(stroke
				(width 0.1)
				(type default)
			)
			(layer "F.Fab")
		)
		(fp_line
			(start 0.67945 0.3048)
			(end 0.120396 0.3048)
			(stroke
				(width 0.1)
				(type default)
			)
			(layer "F.Fab")
		)
		(fp_line
			(start -0.12065 0.2794)
			(end -0.12065 0.3048)
			(stroke
				(width 0.1)
				(type default)
			)
			(layer "F.Fab")
		)
		(fp_line
			(start 0.120396 0.2794)
			(end -0.12065 0.2794)
			(stroke
				(width 0.1)
				(type default)
			)
			(layer "F.Fab")
		)
		(fp_line
			(start -0.12065 -0.2794)
			(end 0.12065 -0.2794)
			(stroke
				(width 0.1)
				(type default)
			)
			(layer "F.Fab")
		)
		(fp_line
			(start 0.12065 -0.2794)
			(end 0.12065 -0.3048)
			(stroke
				(width 0.1)
				(type default)
			)
			(layer "F.Fab")
		)
		(fp_line
			(start 0.12065 -0.3048)
			(end 0.67945 -0.3048)
			(stroke
				(width 0.1)
				(type default)
			)
			(layer "F.Fab")
		)
		(fp_line
			(start 0.67945 -0.3048)
			(end 0.67945 0.3048)
			(stroke
				(width 0.1)
				(type default)
			)
			(layer "F.Fab")
		)
		(fp_line
			(start -0.67945 -0.305054)
			(end -0.12065 -0.305054)
			(stroke
				(width 0.1)
				(type default)
			)
			(layer "F.Fab")
		)
		(fp_line
			(start -0.12065 -0.305054)
			(end -0.12065 -0.2794)
			(stroke
				(width 0.1)
				(type default)
			)
			(layer "F.Fab")
		)
		(pad "1" smd circle
			(at -0.40005 0 270)
			(size 0 0)
			(layers "F.Cu" "F.Mask" "F.Paste")
			(net "GND")
		)
		(pad "2" smd circle
			(at 0.40005 0 270)
			(size 0 0)
			(layers "F.Cu" "F.Mask" "F.Paste")
			(net "P3V3_SSD15")
		)
	)
	(footprint ""
		(layer "F.Cu")
		(at 210.439 -194.691)
		(property "Reference" "C2628"
			(at 0 0 0)
			(layer "F.SilkS")
			(hide yes)
			(effects
				(font
					(size 1.27 1.27)
				)
			)
		)
		(property "Value" ""
			(at 0 0 0)
			(layer "F.Fab")
			(effects
				(font
					(size 1.27 1.27)
				)
			)
		)
		(duplicate_pad_numbers_are_jumpers no)
		(fp_line
			(start -0.7874 -0.4064)
			(end 0.7874 -0.4064)
			(stroke
				(width 0.1524)
				(type default)
			)
			(layer "F.SilkS")
		)
		(fp_line
			(start -0.7874 0.4064)
			(end -0.7874 -0.4064)
			(stroke
				(width 0.1524)
				(type default)
			)
			(layer "F.SilkS")
		)
		(fp_line
			(start 0.7874 -0.4064)
			(end 0.7874 0.4064)
			(stroke
				(width 0.1524)
				(type default)
			)
			(layer "F.SilkS")
		)
		(fp_line
			(start 0.7874 0.4064)
			(end -0.7874 0.4064)
			(stroke
				(width 0.1524)
				(type default)
			)
			(layer "F.SilkS")
		)
		(fp_line
			(start -0.67945 -0.305054)
			(end -0.12065 -0.305054)
			(stroke
				(width 0.1)
				(type default)
			)
			(layer "F.Fab")
		)
		(fp_line
			(start -0.67945 0.3048)
			(end -0.67945 -0.305054)
			(stroke
				(width 0.1)
				(type default)
			)
			(layer "F.Fab")
		)
		(fp_line
			(start -0.12065 -0.305054)
			(end -0.12065 -0.2794)
			(stroke
				(width 0.1)
				(type default)
			)
			(layer "F.Fab")
		)
		(fp_line
			(start -0.12065 -0.2794)
			(end 0.12065 -0.2794)
			(stroke
				(width 0.1)
				(type default)
			)
			(layer "F.Fab")
		)
		(fp_line
			(start -0.12065 0.2794)
			(end -0.12065 0.3048)
			(stroke
				(width 0.1)
				(type default)
			)
			(layer "F.Fab")
		)
		(fp_line
			(start -0.12065 0.3048)
			(end -0.67945 0.3048)
			(stroke
				(width 0.1)
				(type default)
			)
			(layer "F.Fab")
		)
		(fp_line
			(start 0.120396 0.2794)
			(end -0.12065 0.2794)
			(stroke
				(width 0.1)
				(type default)
			)
			(layer "F.Fab")
		)
		(fp_line
			(start 0.120396 0.3048)
			(end 0.120396 0.2794)
			(stroke
				(width 0.1)
				(type default)
			)
			(layer "F.Fab")
		)
		(fp_line
			(start 0.12065 -0.3048)
			(end 0.67945 -0.3048)
			(stroke
				(width 0.1)
				(type default)
			)
			(layer "F.Fab")
		)
		(fp_line
			(start 0.12065 -0.2794)
			(end 0.12065 -0.3048)
			(stroke
				(width 0.1)
				(type default)
			)
			(layer "F.Fab")
		)
		(fp_line
			(start 0.67945 -0.3048)
			(end 0.67945 0.3048)
			(stroke
				(width 0.1)
				(type default)
			)
			(layer "F.Fab")
		)
		(fp_line
			(start 0.67945 0.3048)
			(end 0.120396 0.3048)
			(stroke
				(width 0.1)
				(type default)
			)
			(layer "F.Fab")
		)
		(pad "1" smd circle
			(at -0.40005 0)
			(size 0 0)
			(layers "F.Cu" "F.Mask" "F.Paste")
			(net "GND")
		)
		(pad "2" smd circle
			(at 0.40005 0)
			(size 0 0)
			(layers "F.Cu" "F.Mask" "F.Paste")
			(net "P1V2_AUX")
		)
	)
	(footprint ""
		(layer "F.Cu")
		(at 24.482044 -38.041072 180)
		(property "Reference" "R5873"
			(at 0 0 180)
			(layer "F.SilkS")
			(hide yes)
			(effects
				(font
					(size 1.27 1.27)
				)
			)
		)
		(property "Value" ""
			(at 0 0 180)
			(layer "F.Fab")
			(effects
				(font
					(size 1.27 1.27)
				)
			)
		)
		(duplicate_pad_numbers_are_jumpers no)
		(fp_line
			(start 0.7874 0.4064)
			(end -0.7874 0.4064)
			(stroke
				(width 0.1524)
				(type default)
			)
			(layer "F.SilkS")
		)
		(fp_line
			(start 0.7874 -0.4064)
			(end 0.7874 0.4064)
			(stroke
				(width 0.1524)
				(type default)
			)
			(layer "F.SilkS")
		)
		(fp_line
			(start -0.7874 0.4064)
			(end -0.7874 -0.4064)
			(stroke
				(width 0.1524)
				(type default)
			)
			(layer "F.SilkS")
		)
		(fp_line
			(start -0.7874 -0.4064)
			(end 0.7874 -0.4064)
			(stroke
				(width 0.1524)
				(type default)
			)
			(layer "F.SilkS")
		)
		(fp_line
			(start 0.67945 0.3048)
			(end 0.120396 0.3048)
			(stroke
				(width 0.1)
				(type default)
			)
			(layer "F.Fab")
		)
		(fp_line
			(start 0.67945 -0.3048)
			(end 0.67945 0.3048)
			(stroke
				(width 0.1)
				(type default)
			)
			(layer "F.Fab")
		)
		(fp_line
			(start 0.12065 -0.2794)
			(end 0.12065 -0.3048)
			(stroke
				(width 0.1)
				(type default)
			)
			(layer "F.Fab")
		)
		(fp_line
			(start 0.12065 -0.3048)
			(end 0.67945 -0.3048)
			(stroke
				(width 0.1)
				(type default)
			)
			(layer "F.Fab")
		)
		(fp_line
			(start 0.120396 0.3048)
			(end 0.120396 0.2794)
			(stroke
				(width 0.1)
				(type default)
			)
			(layer "F.Fab")
		)
		(fp_line
			(start 0.120396 0.2794)
			(end -0.12065 0.2794)
			(stroke
				(width 0.1)
				(type default)
			)
			(layer "F.Fab")
		)
		(fp_line
			(start -0.12065 0.3048)
			(end -0.67945 0.3048)
			(stroke
				(width 0.1)
				(type default)
			)
			(layer "F.Fab")
		)
		(fp_line
			(start -0.12065 0.2794)
			(end -0.12065 0.3048)
			(stroke
				(width 0.1)
				(type default)
			)
			(layer "F.Fab")
		)
		(fp_line
			(start -0.12065 -0.2794)
			(end 0.12065 -0.2794)
			(stroke
				(width 0.1)
				(type default)
			)
			(layer "F.Fab")
		)
		(fp_line
			(start -0.12065 -0.305054)
			(end -0.12065 -0.2794)
			(stroke
				(width 0.1)
				(type default)
			)
			(layer "F.Fab")
		)
		(fp_line
			(start -0.67945 0.3048)
			(end -0.67945 -0.305054)
			(stroke
				(width 0.1)
				(type default)
			)
			(layer "F.Fab")
		)
		(fp_line
			(start -0.67945 -0.305054)
			(end -0.12065 -0.305054)
			(stroke
				(width 0.1)
				(type default)
			)
			(layer "F.Fab")
		)
		(pad "1" smd circle
			(at -0.40005 0 180)
			(size 0 0)
			(layers "F.Cu" "F.Mask" "F.Paste")
			(net "P5V_AUX")
		)
		(pad "2" smd circle
			(at 0.40005 0 180)
			(size 0 0)
			(layers "F.Cu" "F.Mask" "F.Paste")
			(net "P3V3_SSD1_PG_G2")
		)
	)
	(footprint ""
		(layer "F.Cu")
		(at 291.194998 -99.750372 180)
		(property "Reference" "R283"
			(at 0 0 180)
			(layer "F.SilkS")
			(hide yes)
			(effects
				(font
					(size 1.27 1.27)
				)
			)
		)
		(property "Value" ""
			(at 0 0 180)
			(layer "F.Fab")
			(effects
				(font
					(size 1.27 1.27)
				)
			)
		)
		(duplicate_pad_numbers_are_jumpers no)
		(fp_line
			(start 0.7874 0.4064)
			(end -0.7874 0.4064)
			(stroke
				(width 0.1524)
				(type default)
			)
			(layer "F.SilkS")
		)
		(fp_line
			(start 0.7874 -0.4064)
			(end 0.7874 0.4064)
			(stroke
				(width 0.1524)
				(type default)
			)
			(layer "F.SilkS")
		)
		(fp_line
			(start -0.7874 0.4064)
			(end -0.7874 -0.4064)
			(stroke
				(width 0.1524)
				(type default)
			)
			(layer "F.SilkS")
		)
		(fp_line
			(start -0.7874 -0.4064)
			(end 0.7874 -0.4064)
			(stroke
				(width 0.1524)
				(type default)
			)
			(layer "F.SilkS")
		)
		(fp_line
			(start 0.67945 0.3048)
			(end 0.120396 0.3048)
			(stroke
				(width 0.1)
				(type default)
			)
			(layer "F.Fab")
		)
		(fp_line
			(start 0.67945 -0.3048)
			(end 0.67945 0.3048)
			(stroke
				(width 0.1)
				(type default)
			)
			(layer "F.Fab")
		)
		(fp_line
			(start 0.12065 -0.2794)
			(end 0.12065 -0.3048)
			(stroke
				(width 0.1)
				(type default)
			)
			(layer "F.Fab")
		)
		(fp_line
			(start 0.12065 -0.3048)
			(end 0.67945 -0.3048)
			(stroke
				(width 0.1)
				(type default)
			)
			(layer "F.Fab")
		)
		(fp_line
			(start 0.120396 0.3048)
			(end 0.120396 0.2794)
			(stroke
				(width 0.1)
				(type default)
			)
			(layer "F.Fab")
		)
		(fp_line
			(start 0.120396 0.2794)
			(end -0.12065 0.2794)
			(stroke
				(width 0.1)
				(type default)
			)
			(layer "F.Fab")
		)
		(fp_line
			(start -0.12065 0.3048)
			(end -0.67945 0.3048)
			(stroke
				(width 0.1)
				(type default)
			)
			(layer "F.Fab")
		)
		(fp_line
			(start -0.12065 0.2794)
			(end -0.12065 0.3048)
			(stroke
				(width 0.1)
				(type default)
			)
			(layer "F.Fab")
		)
		(fp_line
			(start -0.12065 -0.2794)
			(end 0.12065 -0.2794)
			(stroke
				(width 0.1)
				(type default)
			)
			(layer "F.Fab")
		)
		(fp_line
			(start -0.12065 -0.305054)
			(end -0.12065 -0.2794)
			(stroke
				(width 0.1)
				(type default)
			)
			(layer "F.Fab")
		)
		(fp_line
			(start -0.67945 0.3048)
			(end -0.67945 -0.305054)
			(stroke
				(width 0.1)
				(type default)
			)
			(layer "F.Fab")
		)
		(fp_line
			(start -0.67945 -0.305054)
			(end -0.12065 -0.305054)
			(stroke
				(width 0.1)
				(type default)
			)
			(layer "F.Fab")
		)
		(pad "1" smd circle
			(at -0.40005 0 180)
			(size 0 0)
			(layers "F.Cu" "F.Mask" "F.Paste")
			(net "NIC5_SLOT_ID1")
		)
		(pad "2" smd circle
			(at 0.40005 0 180)
			(size 0 0)
			(layers "F.Cu" "F.Mask" "F.Paste")
			(net "GND")
		)
	)
	(footprint ""
		(layer "F.Cu")
		(at 94.494096 -115.394486)
		(property "Reference" "PR6918"
			(at 0 0 0)
			(layer "F.SilkS")
			(hide yes)
			(effects
				(font
					(size 1.27 1.27)
				)
			)
		)
		(property "Value" ""
			(at 0 0 0)
			(layer "F.Fab")
			(effects
				(font
					(size 1.27 1.27)
				)
			)
		)
		(duplicate_pad_numbers_are_jumpers no)
		(fp_line
			(start -0.7874 -0.4064)
			(end 0.7874 -0.4064)
			(stroke
				(width 0.1524)
				(type default)
			)
			(layer "F.SilkS")
		)
		(fp_line
			(start -0.7874 0.4064)
			(end -0.7874 -0.4064)
			(stroke
				(width 0.1524)
				(type default)
			)
			(layer "F.SilkS")
		)
		(fp_line
			(start 0.7874 -0.4064)
			(end 0.7874 0.4064)
			(stroke
				(width 0.1524)
				(type default)
			)
			(layer "F.SilkS")
		)
		(fp_line
			(start 0.7874 0.4064)
			(end -0.7874 0.4064)
			(stroke
				(width 0.1524)
				(type default)
			)
			(layer "F.SilkS")
		)
		(fp_line
			(start -0.67945 -0.305054)
			(end -0.12065 -0.305054)
			(stroke
				(width 0.1)
				(type default)
			)
			(layer "F.Fab")
		)
		(fp_line
			(start -0.67945 0.3048)
			(end -0.67945 -0.305054)
			(stroke
				(width 0.1)
				(type default)
			)
			(layer "F.Fab")
		)
		(fp_line
			(start -0.12065 -0.305054)
			(end -0.12065 -0.2794)
			(stroke
				(width 0.1)
				(type default)
			)
			(layer "F.Fab")
		)
		(fp_line
			(start -0.12065 -0.2794)
			(end 0.12065 -0.2794)
			(stroke
				(width 0.1)
				(type default)
			)
			(layer "F.Fab")
		)
		(fp_line
			(start -0.12065 0.2794)
			(end -0.12065 0.3048)
			(stroke
				(width 0.1)
				(type default)
			)
			(layer "F.Fab")
		)
		(fp_line
			(start -0.12065 0.3048)
			(end -0.67945 0.3048)
			(stroke
				(width 0.1)
				(type default)
			)
			(layer "F.Fab")
		)
		(fp_line
			(start 0.120396 0.2794)
			(end -0.12065 0.2794)
			(stroke
				(width 0.1)
				(type default)
			)
			(layer "F.Fab")
		)
		(fp_line
			(start 0.120396 0.3048)
			(end 0.120396 0.2794)
			(stroke
				(width 0.1)
				(type default)
			)
			(layer "F.Fab")
		)
		(fp_line
			(start 0.12065 -0.3048)
			(end 0.67945 -0.3048)
			(stroke
				(width 0.1)
				(type default)
			)
			(layer "F.Fab")
		)
		(fp_line
			(start 0.12065 -0.2794)
			(end 0.12065 -0.3048)
			(stroke
				(width 0.1)
				(type default)
			)
			(layer "F.Fab")
		)
		(fp_line
			(start 0.67945 -0.3048)
			(end 0.67945 0.3048)
			(stroke
				(width 0.1)
				(type default)
			)
			(layer "F.Fab")
		)
		(fp_line
			(start 0.67945 0.3048)
			(end 0.120396 0.3048)
			(stroke
				(width 0.1)
				(type default)
			)
			(layer "F.Fab")
		)
		(pad "1" smd circle
			(at -0.40005 0)
			(size 0 0)
			(layers "F.Cu" "F.Mask" "F.Paste")
			(net "P3V3_NIC1_CO_ILIMIT")
		)
		(pad "2" smd circle
			(at 0.40005 0)
			(size 0 0)
			(layers "F.Cu" "F.Mask" "F.Paste")
			(net "GND")
		)
	)
	(footprint ""
		(layer "F.Cu")
		(at 326.012556 -198.266304 180)
		(property "Reference" "R4235"
			(at 0 0 180)
			(layer "F.SilkS")
			(hide yes)
			(effects
				(font
					(size 1.27 1.27)
				)
			)
		)
		(property "Value" ""
			(at 0 0 180)
			(layer "F.Fab")
			(effects
				(font
					(size 1.27 1.27)
				)
			)
		)
		(duplicate_pad_numbers_are_jumpers no)
		(fp_line
			(start 0.7874 0.4064)
			(end -0.7874 0.4064)
			(stroke
				(width 0.1524)
				(type default)
			)
			(layer "F.SilkS")
		)
		(fp_line
			(start 0.7874 -0.4064)
			(end 0.7874 0.4064)
			(stroke
				(width 0.1524)
				(type default)
			)
			(layer "F.SilkS")
		)
		(fp_line
			(start -0.7874 0.4064)
			(end -0.7874 -0.4064)
			(stroke
				(width 0.1524)
				(type default)
			)
			(layer "F.SilkS")
		)
		(fp_line
			(start -0.7874 -0.4064)
			(end 0.7874 -0.4064)
			(stroke
				(width 0.1524)
				(type default)
			)
			(layer "F.SilkS")
		)
		(fp_line
			(start 0.67945 0.3048)
			(end 0.120396 0.3048)
			(stroke
				(width 0.1)
				(type default)
			)
			(layer "F.Fab")
		)
		(fp_line
			(start 0.67945 -0.3048)
			(end 0.67945 0.3048)
			(stroke
				(width 0.1)
				(type default)
			)
			(layer "F.Fab")
		)
		(fp_line
			(start 0.12065 -0.2794)
			(end 0.12065 -0.3048)
			(stroke
				(width 0.1)
				(type default)
			)
			(layer "F.Fab")
		)
		(fp_line
			(start 0.12065 -0.3048)
			(end 0.67945 -0.3048)
			(stroke
				(width 0.1)
				(type default)
			)
			(layer "F.Fab")
		)
		(fp_line
			(start 0.120396 0.3048)
			(end 0.120396 0.2794)
			(stroke
				(width 0.1)
				(type default)
			)
			(layer "F.Fab")
		)
		(fp_line
			(start 0.120396 0.2794)
			(end -0.12065 0.2794)
			(stroke
				(width 0.1)
				(type default)
			)
			(layer "F.Fab")
		)
		(fp_line
			(start -0.12065 0.3048)
			(end -0.67945 0.3048)
			(stroke
				(width 0.1)
				(type default)
			)
			(layer "F.Fab")
		)
		(fp_line
			(start -0.12065 0.2794)
			(end -0.12065 0.3048)
			(stroke
				(width 0.1)
				(type default)
			)
			(layer "F.Fab")
		)
		(fp_line
			(start -0.12065 -0.2794)
			(end 0.12065 -0.2794)
			(stroke
				(width 0.1)
				(type default)
			)
			(layer "F.Fab")
		)
		(fp_line
			(start -0.12065 -0.305054)
			(end -0.12065 -0.2794)
			(stroke
				(width 0.1)
				(type default)
			)
			(layer "F.Fab")
		)
		(fp_line
			(start -0.67945 0.3048)
			(end -0.67945 -0.305054)
			(stroke
				(width 0.1)
				(type default)
			)
			(layer "F.Fab")
		)
		(fp_line
			(start -0.67945 -0.305054)
			(end -0.12065 -0.305054)
			(stroke
				(width 0.1)
				(type default)
			)
			(layer "F.Fab")
		)
		(pad "1" smd circle
			(at -0.40005 0 180)
			(size 0 0)
			(layers "F.Cu" "F.Mask" "F.Paste")
			(net "IOEXP_DBV2_A1")
		)
		(pad "2" smd circle
			(at 0.40005 0 180)
			(size 0 0)
			(layers "F.Cu" "F.Mask" "F.Paste")
			(net "P3V3_AUX")
		)
	)
)
